(kicad_pcb
	(version 20241229)
	(generator "pcbnew")
	(generator_version "9.0")
	(general
		(thickness 1.6296)
		(legacy_teardrops no)
	)
	(paper "A3")
	(title_block
		(title "Thunderbolt to 10GbE adapter")
		(date "2026-04-21")
		(rev "1.1.0")
		(company "Antmicro Ltd")
		(comment 1 "www.antmicro.com")
		(comment 9 "footprints 616-620 of 703")
	)
	(layers
		(0 "F.Cu" signal)
		(4 "In1.Cu" signal)
		(6 "In2.Cu" signal)
		(8 "In3.Cu" signal)
		(10 "In4.Cu" signal)
		(12 "In5.Cu" signal)
		(14 "In6.Cu" signal)
		(2 "B.Cu" signal)
		(9 "F.Adhes" user "F.Adhesive")
		(11 "B.Adhes" user "B.Adhesive")
		(13 "F.Paste" user)
		(15 "B.Paste" user)
		(5 "F.SilkS" user "F.Silkscreen")
		(7 "B.SilkS" user "B.Silkscreen")
		(1 "F.Mask" user)
		(3 "B.Mask" user)
		(17 "Dwgs.User" user "User.Drawings")
		(19 "Cmts.User" user "User.Comments")
		(21 "Eco1.User" user "User.Eco1")
		(23 "Eco2.User" user "User.Eco2")
		(25 "Edge.Cuts" user)
		(27 "Margin" user)
		(31 "F.CrtYd" user "F.Courtyard")
		(29 "B.CrtYd" user "B.Courtyard")
		(35 "F.Fab" user)
		(33 "B.Fab" user)
	)
	(footprint "antmicro-footprints:R_0402_1005Metric"
		(layer "B.Cu")
		(at 151.181867 75.285117 180)
		(descr "Resistor SMD 0402")
		(tags "resistor SMD 0402")
		(property "Reference" "R124"
			(at -20.368136 -9.464883 0)
			(layer "B.SilkS")
			(effects
				(font
					(size 0.7 0.7)
					(thickness 0.15)
				)
				(justify mirror)
			)
		)
		(property "Value" "R_100R_0402"
			(at -1.011843 -1.772047 0)
			(layer "B.Fab")
			(effects
				(font
					(size 0.7 0.7)
					(thickness 0.15)
				)
				(justify left bottom mirror)
			)
		)
		(property "Datasheet" "https://www.bourns.com/docs/product-datasheets/cr.pdf"
			(at 0 0 0)
			(layer "B.Fab")
			(hide yes)
			(effects
				(font
					(size 1.27 1.27)
					(thickness 0.15)
				)
				(justify mirror)
			)
		)
		(property "Description" "SMD Chip Resistor, 100 ohm, ± 1%, 62.5 mW, 0402 [1005 Metric], Thick Film, General Purpose"
			(at 0 0 0)
			(layer "B.Fab")
			(hide yes)
			(effects
				(font
					(size 1.27 1.27)
					(thickness 0.15)
				)
				(justify mirror)
			)
		)
		(property "MPN" "CR0402-FX-1000GLF"
			(at 0 0 180)
			(unlocked yes)
			(layer "B.Fab")
			(hide yes)
			(effects
				(font
					(size 1 1)
					(thickness 0.15)
				)
				(justify mirror)
			)
		)
		(property "Manufacturer" "Bourns"
			(at 0 0 180)
			(unlocked yes)
			(layer "B.Fab")
			(hide yes)
			(effects
				(font
					(size 1 1)
					(thickness 0.15)
				)
				(justify mirror)
			)
		)
		(property "License" "Apache-2.0"
			(at 0 0 180)
			(unlocked yes)
			(layer "B.Fab")
			(hide yes)
			(effects
				(font
					(size 1 1)
					(thickness 0.15)
				)
				(justify mirror)
			)
		)
		(property "Author" "Antmicro"
			(at 0 0 180)
			(unlocked yes)
			(layer "B.Fab")
			(hide yes)
			(effects
				(font
					(size 1 1)
					(thickness 0.15)
				)
				(justify mirror)
			)
		)
		(property "Val" "100R"
			(at 0 0 180)
			(unlocked yes)
			(layer "B.Fab")
			(hide yes)
			(effects
				(font
					(size 1 1)
					(thickness 0.15)
				)
				(justify mirror)
			)
		)
		(property "Tolerance" "1%"
			(at 0 0 180)
			(unlocked yes)
			(layer "B.Fab")
			(hide yes)
			(effects
				(font
					(size 1 1)
					(thickness 0.15)
				)
				(justify mirror)
			)
		)
		(sheetname "/X710-AT2 RSVD/")
		(sheetfile "x710-at2-rsvd.kicad_sch")
		(attr smd)
		(fp_rect
			(start -0.925 0.47)
			(end 0.925 -0.47)
			(stroke
				(width 0.05)
				(type default)
			)
			(fill no)
			(layer "B.CrtYd")
		)
		(fp_rect
			(start -0.5 0.25)
			(end 0.5 -0.25)
			(stroke
				(width 0.15)
				(type solid)
			)
			(fill no)
			(layer "B.Fab")
		)
		(fp_text user "License: Apache-2.0"
			(at -0.95 -5.169 0)
			(layer "B.Fab")
			(effects
				(font
					(size 0.7 0.7)
					(thickness 0.15)
				)
				(justify left bottom mirror)
			)
		)
		(fp_text user "${REFERENCE}"
			(at -0.95 -3.168 0)
			(layer "B.Fab")
			(effects
				(font
					(size 0.7 0.7)
					(thickness 0.15)
				)
				(justify left bottom mirror)
			)
		)
		(fp_text user "Author: Antmicro"
			(at -0.95 -4.169 0)
			(layer "B.Fab")
			(effects
				(font
					(size 0.7 0.7)
					(thickness 0.15)
				)
				(justify left bottom mirror)
			)
		)
		(pad "1" smd roundrect
			(at -0.48 0 180)
			(size 0.59 0.64)
			(layers "B.Cu" "B.Mask" "B.Paste")
			(roundrect_rratio 0.25)
			(net 23 "GND")
			(pintype "passive")
		)
		(pad "2" smd roundrect
			(at 0.48 0 180)
			(size 0.59 0.64)
			(layers "B.Cu" "B.Mask" "B.Paste")
			(roundrect_rratio 0.25)
			(net 95 "/X710-AT2 RSVD/RSVDN9_VSS")
			(pintype "passive")
		)
	)
	(footprint "antmicro-footprints:R_0402_1005Metric"
		(layer "B.Cu")
		(at 136.5 125.15)
		(descr "Resistor SMD 0402")
		(tags "resistor SMD 0402")
		(property "Reference" "R52"
			(at 19.525001 -7.450001 180)
			(layer "B.SilkS")
			(effects
				(font
					(size 0.7 0.7)
					(thickness 0.15)
				)
				(justify mirror)
			)
		)
		(property "Value" "R_100k_0402"
			(at -1.011843 -1.772047 180)
			(layer "B.Fab")
			(effects
				(font
					(size 0.7 0.7)
					(thickness 0.15)
				)
				(justify left bottom mirror)
			)
		)
		(property "Datasheet" "https://www.bourns.com/docs/product-datasheets/cr.pdf"
			(at 0 0 180)
			(layer "B.Fab")
			(hide yes)
			(effects
				(font
					(size 1.27 1.27)
					(thickness 0.15)
				)
				(justify mirror)
			)
		)
		(property "Description" "SMD Chip Resistor, 100 kohm, ± 1%, 62.5 mW, 0402 [1005 Metric], Thick Film, General Purpose"
			(at 0 0 180)
			(layer "B.Fab")
			(hide yes)
			(effects
				(font
					(size 1.27 1.27)
					(thickness 0.15)
				)
				(justify mirror)
			)
		)
		(property "MPN" "CR0402-FX-1003GLF"
			(at 0 0 0)
			(unlocked yes)
			(layer "B.Fab")
			(hide yes)
			(effects
				(font
					(size 1 1)
					(thickness 0.15)
				)
				(justify mirror)
			)
		)
		(property "Manufacturer" "Bourns"
			(at 0 0 0)
			(unlocked yes)
			(layer "B.Fab")
			(hide yes)
			(effects
				(font
					(size 1 1)
					(thickness 0.15)
				)
				(justify mirror)
			)
		)
		(property "License" "Apache-2.0"
			(at 0 0 0)
			(unlocked yes)
			(layer "B.Fab")
			(hide yes)
			(effects
				(font
					(size 1 1)
					(thickness 0.15)
				)
				(justify mirror)
			)
		)
		(property "Val" "100k"
			(at 0 0 0)
			(unlocked yes)
			(layer "B.Fab")
			(hide yes)
			(effects
				(font
					(size 1 1)
					(thickness 0.15)
				)
				(justify mirror)
			)
		)
		(property "Tolerance" "1%"
			(at 0 0 0)
			(unlocked yes)
			(layer "B.Fab")
			(hide yes)
			(effects
				(font
					(size 1 1)
					(thickness 0.15)
				)
				(justify mirror)
			)
		)
		(property "Author" "Antmicro"
			(at 0 0 0)
			(unlocked yes)
			(layer "B.Fab")
			(hide yes)
			(effects
				(font
					(size 1 1)
					(thickness 0.15)
				)
				(justify mirror)
			)
		)
		(sheetname "/TB Controller/")
		(sheetfile "tb.kicad_sch")
		(attr smd)
		(fp_rect
			(start -0.925 0.47)
			(end 0.925 -0.47)
			(stroke
				(width 0.05)
				(type default)
			)
			(fill no)
			(layer "B.CrtYd")
		)
		(fp_rect
			(start -0.5 0.25)
			(end 0.5 -0.25)
			(stroke
				(width 0.15)
				(type solid)
			)
			(fill no)
			(layer "B.Fab")
		)
		(fp_text user "${REFERENCE}"
			(at -0.95 -3.168 180)
			(layer "B.Fab")
			(effects
				(font
					(size 0.7 0.7)
					(thickness 0.15)
				)
				(justify left bottom mirror)
			)
		)
		(fp_text user "License: Apache-2.0"
			(at -0.95 -5.169 180)
			(layer "B.Fab")
			(effects
				(font
					(size 0.7 0.7)
					(thickness 0.15)
				)
				(justify left bottom mirror)
			)
		)
		(fp_text user "Author: Antmicro"
			(at -0.95 -4.169 180)
			(layer "B.Fab")
			(effects
				(font
					(size 0.7 0.7)
					(thickness 0.15)
				)
				(justify left bottom mirror)
			)
		)
		(pad "1" smd roundrect
			(at -0.48 0)
			(size 0.59 0.64)
			(layers "B.Cu" "B.Mask" "B.Paste")
			(roundrect_rratio 0.25)
			(net 235 "Net-(U4C-POC_GPIO_5)")
			(pintype "passive")
		)
		(pad "2" smd roundrect
			(at 0.48 0)
			(size 0.59 0.64)
			(layers "B.Cu" "B.Mask" "B.Paste")
			(roundrect_rratio 0.25)
			(net 23 "GND")
			(pintype "passive")
		)
	)
	(footprint "antmicro-footprints:C_0402_1005Metric"
		(layer "B.Cu")
		(at 128.5 122 90)
		(descr "Capacitor SMD 0402")
		(tags "capacitor SMD 0402")
		(property "Reference" "C52"
			(at 7.700002 21.900002 270)
			(layer "B.SilkS")
			(effects
				(font
					(size 0.7 0.7)
					(thickness 0.15)
				)
				(justify mirror)
			)
		)
		(property "Value" "C_1u_0402"
			(at -1.022927 -2.155213 270)
			(layer "B.Fab")
			(effects
				(font
					(size 0.7 0.7)
					(thickness 0.15)
				)
				(justify left bottom mirror)
			)
		)
		(property "Datasheet" "https://product.tdk.com/en/search/capacitor/ceramic/mlcc/info?part_no=C1005X6S1A105K050BC"
			(at 0 0 270)
			(layer "B.Fab")
			(hide yes)
			(effects
				(font
					(size 1.27 1.27)
					(thickness 0.15)
				)
				(justify mirror)
			)
		)
		(property "Description" "SMD Multilayer Ceramic Capacitor, 1 µF, 10 V, 0402 [1005 Metric], ± 10%, X6S, C"
			(at 0 0 270)
			(layer "B.Fab")
			(hide yes)
			(effects
				(font
					(size 1.27 1.27)
					(thickness 0.15)
				)
				(justify mirror)
			)
		)
		(property "MPN" "C1005X6S1A105K050BC"
			(at 0 0 90)
			(unlocked yes)
			(layer "B.Fab")
			(hide yes)
			(effects
				(font
					(size 1 1)
					(thickness 0.15)
				)
				(justify mirror)
			)
		)
		(property "Manufacturer" "TDK"
			(at 0 0 90)
			(unlocked yes)
			(layer "B.Fab")
			(hide yes)
			(effects
				(font
					(size 1 1)
					(thickness 0.15)
				)
				(justify mirror)
			)
		)
		(property "License" "Apache-2.0"
			(at 0 0 90)
			(unlocked yes)
			(layer "B.Fab")
			(hide yes)
			(effects
				(font
					(size 1 1)
					(thickness 0.15)
				)
				(justify mirror)
			)
		)
		(property "Val" "1u"
			(at 0 0 90)
			(unlocked yes)
			(layer "B.Fab")
			(hide yes)
			(effects
				(font
					(size 1 1)
					(thickness 0.15)
				)
				(justify mirror)
			)
		)
		(property "Voltage" ""
			(at 0 0 90)
			(unlocked yes)
			(layer "B.Fab")
			(hide yes)
			(effects
				(font
					(size 1 1)
					(thickness 0.15)
				)
				(justify mirror)
			)
		)
		(property "Dielectric" ""
			(at 0 0 90)
			(unlocked yes)
			(layer "B.Fab")
			(hide yes)
			(effects
				(font
					(size 1 1)
					(thickness 0.15)
				)
				(justify mirror)
			)
		)
		(property "Author" "Antmicro"
			(at 0 0 90)
			(unlocked yes)
			(layer "B.Fab")
			(hide yes)
			(effects
				(font
					(size 1 1)
					(thickness 0.15)
				)
				(justify mirror)
			)
		)
		(sheetname "/TB Controller - Power/")
		(sheetfile "tb-power.kicad_sch")
		(attr smd)
		(fp_rect
			(start -0.925 0.47)
			(end 0.925 -0.47)
			(stroke
				(width 0.05)
				(type default)
			)
			(fill no)
			(layer "B.CrtYd")
		)
		(fp_line
			(start 0.504 -0.248)
			(end -0.494 -0.248)
			(stroke
				(width 0.15)
				(type solid)
			)
			(layer "B.Fab")
		)
		(fp_line
			(start -0.494 -0.248)
			(end -0.494 0.25)
			(stroke
				(width 0.15)
				(type solid)
			)
			(layer "B.Fab")
		)
		(fp_line
			(start 0.504 0.25)
			(end 0.504 -0.248)
			(stroke
				(width 0.15)
				(type solid)
			)
			(layer "B.Fab")
		)
		(fp_line
			(start -0.494 0.25)
			(end 0.504 0.25)
			(stroke
				(width 0.15)
				(type solid)
			)
			(layer "B.Fab")
		)
		(fp_text user "License: Apache-2.0"
			(at -0.939 -5.799 270)
			(layer "B.Fab")
			(effects
				(font
					(size 0.7 0.7)
					(thickness 0.15)
				)
				(justify left bottom mirror)
			)
		)
		(fp_text user "${REFERENCE}"
			(at -0.939 -4.599 270)
			(layer "B.Fab")
			(effects
				(font
					(size 0.7 0.7)
					(thickness 0.15)
				)
				(justify left bottom mirror)
			)
		)
		(fp_text user "Author: Antmicro"
			(at -0.939 -3.399 270)
			(layer "B.Fab")
			(effects
				(font
					(size 0.7 0.7)
					(thickness 0.15)
				)
				(justify left bottom mirror)
			)
		)
		(pad "1" smd roundrect
			(at -0.48 0 90)
			(size 0.59 0.64)
			(layers "B.Cu" "B.Mask" "B.Paste")
			(roundrect_rratio 0.25)
			(net 23 "GND")
			(pintype "passive")
		)
		(pad "2" smd roundrect
			(at 0.48 0 90)
			(size 0.59 0.64)
			(layers "B.Cu" "B.Mask" "B.Paste")
			(roundrect_rratio 0.25)
			(net 402 "Net-(C52-Pad2)")
			(pintype "passive")
		)
	)
	(footprint "antmicro-footprints:C_0402_1005Metric"
		(layer "B.Cu")
		(at 127.049999 127.350001)
		(descr "Capacitor SMD 0402")
		(tags "capacitor SMD 0402")
		(property "Reference" "C88"
			(at 21.900002 -7.700002 180)
			(layer "B.SilkS")
			(effects
				(font
					(size 0.7 0.7)
					(thickness 0.15)
				)
				(justify mirror)
			)
		)
		(property "Value" "C_1u_0402"
			(at -1.022927 -2.155213 180)
			(layer "B.Fab")
			(effects
				(font
					(size 0.7 0.7)
					(thickness 0.15)
				)
				(justify left bottom mirror)
			)
		)
		(property "Datasheet" "https://product.tdk.com/en/search/capacitor/ceramic/mlcc/info?part_no=C1005X6S1A105K050BC"
			(at 0 0 180)
			(layer "B.Fab")
			(hide yes)
			(effects
				(font
					(size 1.27 1.27)
					(thickness 0.15)
				)
				(justify mirror)
			)
		)
		(property "Description" "SMD Multilayer Ceramic Capacitor, 1 µF, 10 V, 0402 [1005 Metric], ± 10%, X6S, C"
			(at 0 0 180)
			(layer "B.Fab")
			(hide yes)
			(effects
				(font
					(size 1.27 1.27)
					(thickness 0.15)
				)
				(justify mirror)
			)
		)
		(property "MPN" "C1005X6S1A105K050BC"
			(at 0 0 0)
			(unlocked yes)
			(layer "B.Fab")
			(hide yes)
			(effects
				(font
					(size 1 1)
					(thickness 0.15)
				)
				(justify mirror)
			)
		)
		(property "Manufacturer" "TDK"
			(at 0 0 0)
			(unlocked yes)
			(layer "B.Fab")
			(hide yes)
			(effects
				(font
					(size 1 1)
					(thickness 0.15)
				)
				(justify mirror)
			)
		)
		(property "License" "Apache-2.0"
			(at 0 0 0)
			(unlocked yes)
			(layer "B.Fab")
			(hide yes)
			(effects
				(font
					(size 1 1)
					(thickness 0.15)
				)
				(justify mirror)
			)
		)
		(property "Val" "1u"
			(at 0 0 0)
			(unlocked yes)
			(layer "B.Fab")
			(hide yes)
			(effects
				(font
					(size 1 1)
					(thickness 0.15)
				)
				(justify mirror)
			)
		)
		(property "Voltage" ""
			(at 0 0 0)
			(unlocked yes)
			(layer "B.Fab")
			(hide yes)
			(effects
				(font
					(size 1 1)
					(thickness 0.15)
				)
				(justify mirror)
			)
		)
		(property "Dielectric" ""
			(at 0 0 0)
			(unlocked yes)
			(layer "B.Fab")
			(hide yes)
			(effects
				(font
					(size 1 1)
					(thickness 0.15)
				)
				(justify mirror)
			)
		)
		(property "Author" "Antmicro"
			(at 0 0 0)
			(unlocked yes)
			(layer "B.Fab")
			(hide yes)
			(effects
				(font
					(size 1 1)
					(thickness 0.15)
				)
				(justify mirror)
			)
		)
		(sheetname "/TB Controller - Power/")
		(sheetfile "tb-power.kicad_sch")
		(attr smd)
		(fp_rect
			(start -0.925 0.47)
			(end 0.925 -0.47)
			(stroke
				(width 0.05)
				(type default)
			)
			(fill no)
			(layer "B.CrtYd")
		)
		(fp_line
			(start -0.494 -0.248)
			(end -0.494 0.25)
			(stroke
				(width 0.15)
				(type solid)
			)
			(layer "B.Fab")
		)
		(fp_line
			(start -0.494 0.25)
			(end 0.504 0.25)
			(stroke
				(width 0.15)
				(type solid)
			)
			(layer "B.Fab")
		)
		(fp_line
			(start 0.504 -0.248)
			(end -0.494 -0.248)
			(stroke
				(width 0.15)
				(type solid)
			)
			(layer "B.Fab")
		)
		(fp_line
			(start 0.504 0.25)
			(end 0.504 -0.248)
			(stroke
				(width 0.15)
				(type solid)
			)
			(layer "B.Fab")
		)
		(fp_text user "License: Apache-2.0"
			(at -0.939 -5.799 180)
			(layer "B.Fab")
			(effects
				(font
					(size 0.7 0.7)
					(thickness 0.15)
				)
				(justify left bottom mirror)
			)
		)
		(fp_text user "${REFERENCE}"
			(at -0.939 -4.599 180)
			(layer "B.Fab")
			(effects
				(font
					(size 0.7 0.7)
					(thickness 0.15)
				)
				(justify left bottom mirror)
			)
		)
		(fp_text user "Author: Antmicro"
			(at -0.939 -3.399 180)
			(layer "B.Fab")
			(effects
				(font
					(size 0.7 0.7)
					(thickness 0.15)
				)
				(justify left bottom mirror)
			)
		)
		(pad "1" smd roundrect
			(at -0.48 0)
			(size 0.59 0.64)
			(layers "B.Cu" "B.Mask" "B.Paste")
			(roundrect_rratio 0.25)
			(net 23 "GND")
			(pintype "passive")
		)
		(pad "2" smd roundrect
			(at 0.48 0)
			(size 0.59 0.64)
			(layers "B.Cu" "B.Mask" "B.Paste")
			(roundrect_rratio 0.25)
			(net 68 "/TB Controller - Power/VCC_0P9")
			(pintype "passive")
		)
	)
	(footprint "antmicro-footprints:R_0402_1005Metric"
		(layer "B.Cu")
		(at 135.840001 135.089997 90)
		(descr "Resistor SMD 0402")
		(tags "resistor SMD 0402")
		(property "Reference" "R19"
			(at 8.339997 19.525001 270)
			(layer "B.SilkS")
			(effects
				(font
					(size 0.7 0.7)
					(thickness 0.15)
				)
				(justify mirror)
			)
		)
		(property "Value" "R_1M_0402"
			(at -1.011843 -1.772047 270)
			(layer "B.Fab")
			(effects
				(font
					(size 0.7 0.7)
					(thickness 0.15)
				)
				(justify left bottom mirror)
			)
		)
		(property "Datasheet" "https://www.bourns.com/docs/product-datasheets/cr.pdf"
			(at 0 0 270)
			(layer "B.Fab")
			(hide yes)
			(effects
				(font
					(size 1.27 1.27)
					(thickness 0.15)
				)
				(justify mirror)
			)
		)
		(property "Description" "SMD Chip Resistor, 1 Mohm, ± 1%, 62.5 mW, 0402 [1005 Metric], Thick Film, General Purpose"
			(at 0 0 270)
			(layer "B.Fab")
			(hide yes)
			(effects
				(font
					(size 1.27 1.27)
					(thickness 0.15)
				)
				(justify mirror)
			)
		)
		(property "MPN" "CR0402-FX-1004GLF"
			(at 0 0 90)
			(unlocked yes)
			(layer "B.Fab")
			(hide yes)
			(effects
				(font
					(size 1 1)
					(thickness 0.15)
				)
				(justify mirror)
			)
		)
		(property "Manufacturer" "Bourns"
			(at 0 0 90)
			(unlocked yes)
			(layer "B.Fab")
			(hide yes)
			(effects
				(font
					(size 1 1)
					(thickness 0.15)
				)
				(justify mirror)
			)
		)
		(property "License" "Apache-2.0"
			(at 0 0 90)
			(unlocked yes)
			(layer "B.Fab")
			(hide yes)
			(effects
				(font
					(size 1 1)
					(thickness 0.15)
				)
				(justify mirror)
			)
		)
		(property "Val" "1M"
			(at 0 0 90)
			(unlocked yes)
			(layer "B.Fab")
			(hide yes)
			(effects
				(font
					(size 1 1)
					(thickness 0.15)
				)
				(justify mirror)
			)
		)
		(property "Tolerance" "1%"
			(at 0 0 90)
			(unlocked yes)
			(layer "B.Fab")
			(hide yes)
			(effects
				(font
					(size 1 1)
					(thickness 0.15)
				)
				(justify mirror)
			)
		)
		(property "Author" "Antmicro"
			(at 0 0 90)
			(unlocked yes)
			(layer "B.Fab")
			(hide yes)
			(effects
				(font
					(size 1 1)
					(thickness 0.15)
				)
				(justify mirror)
			)
		)
		(sheetname "/PD and TB DC-DC/")
		(sheetfile "PD_and_TB_DC_DC.kicad_sch")
		(attr smd)
		(fp_rect
			(start -0.925 0.47)
			(end 0.925 -0.47)
			(stroke
				(width 0.05)
				(type default)
			)
			(fill no)
			(layer "B.CrtYd")
		)
		(fp_rect
			(start -0.5 0.25)
			(end 0.5 -0.25)
			(stroke
				(width 0.15)
				(type solid)
			)
			(fill no)
			(layer "B.Fab")
		)
		(fp_text user "Author: Antmicro"
			(at -0.95 -4.169 270)
			(layer "B.Fab")
			(effects
				(font
					(size 0.7 0.7)
					(thickness 0.15)
				)
				(justify left bottom mirror)
			)
		)
		(fp_text user "${REFERENCE}"
			(at -0.95 -3.168 270)
			(layer "B.Fab")
			(effects
				(font
					(size 0.7 0.7)
					(thickness 0.15)
				)
				(justify left bottom mirror)
			)
		)
		(fp_text user "License: Apache-2.0"
			(at -0.95 -5.169 270)
			(layer "B.Fab")
			(effects
				(font
					(size 0.7 0.7)
					(thickness 0.15)
				)
				(justify left bottom mirror)
			)
		)
		(pad "1" smd roundrect
			(at -0.48 0 90)
			(size 0.59 0.64)
			(layers "B.Cu" "B.Mask" "B.Paste")
			(roundrect_rratio 0.25)
			(net 23 "GND")
			(pintype "passive")
		)
		(pad "2" smd roundrect
			(at 0.48 0 90)
			(size 0.59 0.64)
			(layers "B.Cu" "B.Mask" "B.Paste")
			(roundrect_rratio 0.25)
			(net 205 "Net-(U3-UART_RX)")
			(pintype "passive")
		)
	)
)
